(kicad_pcb
	(version 20241229)
	(generator "pcbnew")
	(generator_version "9.0")
	(general
		(thickness 1.711)
		(legacy_teardrops no)
	)
	(paper "A4")
	(title_block
		(title "Antmicro Baseboard for Jetson AGX Thor")
		(date "2026-02-18")
		(rev "1.1.0")
		(company "Antmicro Ltd")
		(comment 1 "www.antmicro.com")
		(comment 9 "footprints 1071-1073 of 1170")
	)
	(layers
		(0 "F.Cu" signal)
		(4 "In1.Cu" signal)
		(6 "In2.Cu" signal)
		(8 "In3.Cu" signal)
		(10 "In4.Cu" jumper)
		(12 "In5.Cu" signal)
		(14 "In6.Cu" signal)
		(16 "In7.Cu" signal)
		(18 "In8.Cu" signal)
		(2 "B.Cu" signal)
		(9 "F.Adhes" user "F.Adhesive")
		(11 "B.Adhes" user "B.Adhesive")
		(13 "F.Paste" user)
		(15 "B.Paste" user)
		(5 "F.SilkS" user "F.Silkscreen")
		(7 "B.SilkS" user "B.Silkscreen")
		(1 "F.Mask" user)
		(3 "B.Mask" user)
		(17 "Dwgs.User" user "User.Drawings")
		(19 "Cmts.User" user "User.Comments")
		(21 "Eco1.User" user "User.Eco1")
		(23 "Eco2.User" user "User.Eco2")
		(25 "Edge.Cuts" user)
		(27 "Margin" user)
		(31 "F.CrtYd" user "F.Courtyard")
		(29 "B.CrtYd" user "B.Courtyard")
		(35 "F.Fab" user)
		(33 "B.Fab" user)
	)
	(footprint "antmicro-footprints:C_0402_1005Metric"
		(layer "B.Cu")
		(at 235.9 135)
		(descr "Capacitor SMD 0402")
		(tags "capacitor SMD 0402")
		(property "Reference" "C104"
			(at 1.084 -0.413 0)
			(layer "B.SilkS")
			(effects
				(font
					(size 0.7 0.7)
					(thickness 0.15)
				)
				(justify right top mirror)
			)
		)
		(property "Value" "C_100n_0402"
			(at -1.022927 -2.155213 0)
			(layer "B.Fab")
			(effects
				(font
					(size 0.7 0.7)
					(thickness 0.15)
				)
				(justify right top mirror)
			)
		)
		(property "Datasheet" "https://www.murata.com/products/productdetail?partno=GRM155R61H104KE14%23"
			(at 0 0 0)
			(layer "B.Fab")
			(hide yes)
			(effects
				(font
					(size 1.27 1.27)
					(thickness 0.15)
				)
				(justify mirror)
			)
		)
		(property "Description" "SMD Multilayer Ceramic Capacitor, 0.1 µF, 50 V, 0402 [1005 Metric], ± 10%, X5R, GRM Series"
			(at 0 0 0)
			(layer "B.Fab")
			(hide yes)
			(effects
				(font
					(size 1.27 1.27)
					(thickness 0.15)
				)
				(justify mirror)
			)
		)
		(property "Manufacturer" "Murata"
			(at 0 0 180)
			(unlocked yes)
			(layer "B.Fab")
			(hide yes)
			(effects
				(font
					(size 1 1)
					(thickness 0.15)
				)
				(justify mirror)
			)
		)
		(property "MPN" "GRM155R61H104KE14D"
			(at 0 0 180)
			(unlocked yes)
			(layer "B.Fab")
			(hide yes)
			(effects
				(font
					(size 1 1)
					(thickness 0.15)
				)
				(justify mirror)
			)
		)
		(property "Val" "100n"
			(at 0 0 180)
			(unlocked yes)
			(layer "B.Fab")
			(hide yes)
			(effects
				(font
					(size 1 1)
					(thickness 0.15)
				)
				(justify mirror)
			)
		)
		(property "License" "Apache-2.0"
			(at 0 0 180)
			(unlocked yes)
			(layer "B.Fab")
			(hide yes)
			(effects
				(font
					(size 1 1)
					(thickness 0.15)
				)
				(justify mirror)
			)
		)
		(property "Author" "Antmicro"
			(at 0 0 180)
			(unlocked yes)
			(layer "B.Fab")
			(hide yes)
			(effects
				(font
					(size 1 1)
					(thickness 0.15)
				)
				(justify mirror)
			)
		)
		(property "Voltage" "50V"
			(at 0 0 180)
			(unlocked yes)
			(layer "B.Fab")
			(hide yes)
			(effects
				(font
					(size 1 1)
					(thickness 0.15)
				)
				(justify mirror)
			)
		)
		(property "Dielectric" "X5R"
			(at 0 0 180)
			(unlocked yes)
			(layer "B.Fab")
			(hide yes)
			(effects
				(font
					(size 1 1)
					(thickness 0.15)
				)
				(justify mirror)
			)
		)
		(sheetname "/USB Hub/")
		(sheetfile "usb_hub.kicad_sch")
		(attr smd)
		(fp_poly
			(pts
				(xy -0.925 0.47) (xy -0.925 -0.47) (xy 0.925 -0.47) (xy 0.925 0.47)
			)
			(stroke
				(width 0.05)
				(type default)
			)
			(fill no)
			(layer "B.CrtYd")
		)
		(fp_line
			(start -0.494 -0.248)
			(end -0.494 0.25)
			(stroke
				(width 0.15)
				(type solid)
			)
			(layer "B.Fab")
		)
		(fp_line
			(start -0.494 0.25)
			(end 0.504 0.25)
			(stroke
				(width 0.15)
				(type solid)
			)
			(layer "B.Fab")
		)
		(fp_line
			(start 0.504 -0.248)
			(end -0.494 -0.248)
			(stroke
				(width 0.15)
				(type solid)
			)
			(layer "B.Fab")
		)
		(fp_line
			(start 0.504 0.25)
			(end 0.504 -0.248)
			(stroke
				(width 0.15)
				(type solid)
			)
			(layer "B.Fab")
		)
		(fp_text user "${REFERENCE}"
			(at -0.939 -4.599 0)
			(layer "B.Fab")
			(effects
				(font
					(size 0.7 0.7)
					(thickness 0.15)
				)
				(justify right top mirror)
			)
		)
		(fp_text user "License: Apache-2.0"
			(at -0.939 -5.799 0)
			(layer "B.Fab")
			(effects
				(font
					(size 0.7 0.7)
					(thickness 0.15)
				)
				(justify right top mirror)
			)
		)
		(fp_text user "Author: Antmicro"
			(at -0.939 -3.399 0)
			(layer "B.Fab")
			(effects
				(font
					(size 0.7 0.7)
					(thickness 0.15)
				)
				(justify right top mirror)
			)
		)
		(pad "1" smd roundrect
			(at -0.48 0)
			(size 0.59 0.64)
			(layers "B.Cu" "B.Mask" "B.Paste")
			(roundrect_rratio 0.25)
			(net 5 "+5V")
			(pintype "passive")
		)
		(pad "2" smd roundrect
			(at 0.48 0)
			(size 0.59 0.64)
			(layers "B.Cu" "B.Mask" "B.Paste")
			(roundrect_rratio 0.25)
			(net 1 "GND")
			(pintype "passive")
		)
	)
	(footprint "antmicro-footprints:Spacer_Drill3.7mm_H8mm_9774080151R"
		(locked yes)
		(layer "B.Cu")
		(at 152.430532 143.71 180)
		(descr "Spacer M=3 h=8mm fi=5.1mm")
		(property "Reference" "H12"
			(at 0 3.2 0)
			(layer "B.SilkS")
			(effects
				(font
					(size 0.7 0.7)
					(thickness 0.15)
				)
				(justify left bottom mirror)
			)
		)
		(property "Value" "Spacer_Drill3.7mm_H8mm_9774080151R"
			(at 0 -4 0)
			(layer "B.Fab")
			(effects
				(font
					(size 0.7 0.7)
					(thickness 0.15)
				)
				(justify left bottom mirror)
			)
		)
		(property "Datasheet" "https://www.we-online.com/components/products/datasheet/9774080151R.pdf"
			(at 0 0 0)
			(layer "B.Fab")
			(hide yes)
			(effects
				(font
					(size 1.27 1.27)
					(thickness 0.15)
				)
				(justify mirror)
			)
		)
		(property "Description" "Spacer, SMT, Non Stop, Steel, Swage Round, 5.1 mm x 8 mm, M2.5 Thread, WA-SMSI Series"
			(at 0 0 0)
			(layer "B.Fab")
			(hide yes)
			(effects
				(font
					(size 1.27 1.27)
					(thickness 0.15)
				)
				(justify mirror)
			)
		)
		(property "Manufacturer" "Würth Elektronik"
			(at 0 0 180)
			(unlocked yes)
			(layer "B.Fab")
			(hide yes)
			(effects
				(font
					(size 1 1)
					(thickness 0.15)
				)
				(justify mirror)
			)
		)
		(property "MPN" "9774080151R"
			(at 0 0 180)
			(unlocked yes)
			(layer "B.Fab")
			(hide yes)
			(effects
				(font
					(size 1 1)
					(thickness 0.15)
				)
				(justify mirror)
			)
		)
		(property "Author" "Antmicro"
			(at 0 0 180)
			(unlocked yes)
			(layer "B.Fab")
			(hide yes)
			(effects
				(font
					(size 1 1)
					(thickness 0.15)
				)
				(justify mirror)
			)
		)
		(property "License" "Apache-2.0"
			(at 0 0 180)
			(unlocked yes)
			(layer "B.Fab")
			(hide yes)
			(effects
				(font
					(size 1 1)
					(thickness 0.15)
				)
				(justify mirror)
			)
		)
		(sheetname "/")
		(sheetfile "jetson-agx-thor-baseboard.kicad_sch")
		(solder_paste_margin_ratio -1)
		(attr smd)
		(fp_circle
			(center 0 0)
			(end 3.05 0)
			(stroke
				(width 0.05)
				(type solid)
			)
			(fill no)
			(layer "B.CrtYd")
		)
		(fp_circle
			(center 0 0)
			(end 2.6 0)
			(stroke
				(width 0.15)
				(type solid)
			)
			(fill no)
			(layer "B.Fab")
		)
		(fp_text user "${REFERENCE}"
			(at -9.6 -6.5 0)
			(layer "B.Fab")
			(effects
				(font
					(size 0.7 0.7)
					(thickness 0.15)
				)
				(justify left bottom mirror)
			)
		)
		(fp_text user "Author: Antmicro"
			(at -9.6 -7.7 0)
			(layer "B.Fab")
			(effects
				(font
					(size 0.7 0.7)
					(thickness 0.15)
				)
				(justify left bottom mirror)
			)
		)
		(fp_text user "License: Apache-2.0"
			(at -9.6 -8.9 0)
			(layer "B.Fab")
			(effects
				(font
					(size 0.7 0.7)
					(thickness 0.15)
				)
				(justify left bottom mirror)
			)
		)
		(pad "" smd custom
			(at -1.7 -1.7 90)
			(size 0.62 0.62)
			(layers "B.Paste")
			(thermal_bridge_angle 90)
			(options
				(clearance outline)
				(anchor circle)
			)
			(primitives
				(gr_arc
					(start 1.266786 0.24747)
					(mid 0.285453 -0.29439)
					(end -0.250195 -1.279127)
					(width 0.2)
				)
				(gr_arc
					(start 1.259603 0.339191)
					(mid 0.218448 -0.232561)
					(end -0.34334 -1.279127)
					(width 0.2)
				)
				(gr_arc
					(start 1.255279 0.431435)
					(mid 0.152481 -0.169693)
					(end -0.436309 -1.279127)
					(width 0.2)
				)
				(gr_arc
					(start 1.253811 0.524161)
					(mid 0.087542 -0.105784)
					(end -0.529126 -1.279127)
					(width 0.2)
				)
				(gr_arc
					(start 1.275473 0.621136)
					(mid 0.0309 -0.033527)
					(end -0.621807 -1.279127)
					(width 0.2)
				)
				(gr_arc
					(start 1.263664 0.711602)
					(mid -0.037759 0.026651)
					(end -0.71437 -1.279127)
					(width 0.2)
				)
				(gr_arc
					(start 1.253435 0.802342)
					(mid -0.105837 0.087395)
					(end -0.806826 -1.279127)
					(width 0.2)
				)
				(gr_arc
					(start 1.267475 0.897258)
					(mid -0.165236 0.156885)
					(end -0.899187 -1.279127)
					(width 0.2)
				)
				(gr_arc
					(start 1.270645 0.990112)
					(mid -0.228522 0.222449)
					(end -0.991463 -1.279127)
					(width 0.2)
				)
				(gr_arc
					(start 1.266278 1.081674)
					(mid -0.294507 0.285313)
					(end -1.083663 -1.279127)
					(width 0.2)
				)
				(gr_line
					(start 1.279127 0.250195)
					(end 1.279127 1.083663)
					(width 0.2)
				)
				(gr_line
					(start -0.250195 -1.279127)
					(end -1.083663 -1.279127)
					(width 0.2)
				)
			)
		)
		(pad "" smd custom
			(at -1.7 1.7 180)
			(size 0.62 0.62)
			(layers "B.Paste")
			(thermal_bridge_angle 90)
			(options
				(clearance outline)
				(anchor circle)
			)
			(primitives
				(gr_arc
					(start 1.266786 0.24747)
					(mid 0.285453 -0.29439)
					(end -0.250195 -1.279127)
					(width 0.2)
				)
				(gr_arc
					(start 1.259603 0.339191)
					(mid 0.218448 -0.232561)
					(end -0.34334 -1.279127)
					(width 0.2)
				)
				(gr_arc
					(start 1.255279 0.431435)
					(mid 0.152481 -0.169693)
					(end -0.436309 -1.279127)
					(width 0.2)
				)
				(gr_arc
					(start 1.253811 0.524161)
					(mid 0.087542 -0.105784)
					(end -0.529126 -1.279127)
					(width 0.2)
				)
				(gr_arc
					(start 1.275473 0.621136)
					(mid 0.0309 -0.033527)
					(end -0.621807 -1.279127)
					(width 0.2)
				)
				(gr_arc
					(start 1.263664 0.711602)
					(mid -0.037759 0.026651)
					(end -0.71437 -1.279127)
					(width 0.2)
				)
				(gr_arc
					(start 1.253435 0.802342)
					(mid -0.105837 0.087395)
					(end -0.806826 -1.279127)
					(width 0.2)
				)
				(gr_arc
					(start 1.267475 0.897258)
					(mid -0.165236 0.156885)
					(end -0.899187 -1.279127)
					(width 0.2)
				)
				(gr_arc
					(start 1.270645 0.990112)
					(mid -0.228522 0.222449)
					(end -0.991463 -1.279127)
					(width 0.2)
				)
				(gr_arc
					(start 1.266278 1.081674)
					(mid -0.294507 0.285313)
					(end -1.083663 -1.279127)
					(width 0.2)
				)
				(gr_line
					(start 1.279127 0.250195)
					(end 1.279127 1.083663)
					(width 0.2)
				)
				(gr_line
					(start -0.250195 -1.279127)
					(end -1.083663 -1.279127)
					(width 0.2)
				)
			)
		)
		(pad "" smd custom
			(at 1.7 -1.7)
			(size 0.62 0.62)
			(layers "B.Paste")
			(thermal_bridge_angle 90)
			(options
				(clearance outline)
				(anchor circle)
			)
			(primitives
				(gr_arc
					(start 1.266786 0.24747)
					(mid 0.285453 -0.29439)
					(end -0.250195 -1.279127)
					(width 0.2)
				)
				(gr_arc
					(start 1.259603 0.339191)
					(mid 0.218448 -0.232561)
					(end -0.34334 -1.279127)
					(width 0.2)
				)
				(gr_arc
					(start 1.255279 0.431435)
					(mid 0.152481 -0.169693)
					(end -0.436309 -1.279127)
					(width 0.2)
				)
				(gr_arc
					(start 1.253811 0.524161)
					(mid 0.087542 -0.105784)
					(end -0.529126 -1.279127)
					(width 0.2)
				)
				(gr_arc
					(start 1.275473 0.621136)
					(mid 0.0309 -0.033527)
					(end -0.621807 -1.279127)
					(width 0.2)
				)
				(gr_arc
					(start 1.263664 0.711602)
					(mid -0.037759 0.026651)
					(end -0.71437 -1.279127)
					(width 0.2)
				)
				(gr_arc
					(start 1.253435 0.802342)
					(mid -0.105837 0.087395)
					(end -0.806826 -1.279127)
					(width 0.2)
				)
				(gr_arc
					(start 1.267475 0.897258)
					(mid -0.165236 0.156885)
					(end -0.899187 -1.279127)
					(width 0.2)
				)
				(gr_arc
					(start 1.270645 0.990112)
					(mid -0.228522 0.222449)
					(end -0.991463 -1.279127)
					(width 0.2)
				)
				(gr_arc
					(start 1.266278 1.081674)
					(mid -0.294507 0.285313)
					(end -1.083663 -1.279127)
					(width 0.2)
				)
				(gr_line
					(start 1.279127 0.250195)
					(end 1.279127 1.083663)
					(width 0.2)
				)
				(gr_line
					(start -0.250195 -1.279127)
					(end -1.083663 -1.279127)
					(width 0.2)
				)
			)
		)
		(pad "" smd custom
			(at 1.7 1.7 270)
			(size 0.62 0.62)
			(layers "B.Paste")
			(thermal_bridge_angle 90)
			(options
				(clearance outline)
				(anchor circle)
			)
			(primitives
				(gr_arc
					(start 1.266786 0.24747)
					(mid 0.285453 -0.29439)
					(end -0.250195 -1.279127)
					(width 0.2)
				)
				(gr_arc
					(start 1.259603 0.339191)
					(mid 0.218448 -0.232561)
					(end -0.34334 -1.279127)
					(width 0.2)
				)
				(gr_arc
					(start 1.255279 0.431435)
					(mid 0.152481 -0.169693)
					(end -0.436309 -1.279127)
					(width 0.2)
				)
				(gr_arc
					(start 1.253811 0.524161)
					(mid 0.087542 -0.105784)
					(end -0.529126 -1.279127)
					(width 0.2)
				)
				(gr_arc
					(start 1.275473 0.621136)
					(mid 0.0309 -0.033527)
					(end -0.621807 -1.279127)
					(width 0.2)
				)
				(gr_arc
					(start 1.263664 0.711602)
					(mid -0.037759 0.026651)
					(end -0.71437 -1.279127)
					(width 0.2)
				)
				(gr_arc
					(start 1.253435 0.802342)
					(mid -0.105837 0.087395)
					(end -0.806826 -1.279127)
					(width 0.2)
				)
				(gr_arc
					(start 1.267475 0.897258)
					(mid -0.165236 0.156885)
					(end -0.899187 -1.279127)
					(width 0.2)
				)
				(gr_arc
					(start 1.270645 0.990112)
					(mid -0.228522 0.222449)
					(end -0.991463 -1.279127)
					(width 0.2)
				)
				(gr_arc
					(start 1.266278 1.081674)
					(mid -0.294507 0.285313)
					(end -1.083663 -1.279127)
					(width 0.2)
				)
				(gr_line
					(start 1.279127 0.250195)
					(end 1.279127 1.083663)
					(width 0.2)
				)
				(gr_line
					(start -0.250195 -1.279127)
					(end -1.083663 -1.279127)
					(width 0.2)
				)
			)
		)
		(pad "1" thru_hole circle
			(at 0 0 180)
			(size 6 6)
			(drill 3.7)
			(layers "*.Cu" "*.Mask")
			(remove_unused_layers no)
			(net 1 "GND")
			(pintype "passive")
		)
	)
	(footprint "antmicro-footprints:C_0402_1005Metric"
		(layer "B.Cu")
		(at 230.07 103.6 180)
		(descr "Capacitor SMD 0402")
		(tags "capacitor SMD 0402")
		(property "Reference" "C116"
			(at 0.9 -0.4 0)
			(layer "B.SilkS")
			(effects
				(font
					(size 0.7 0.7)
					(thickness 0.15)
				)
				(justify left bottom mirror)
			)
		)
		(property "Value" "C_100n_0402"
			(at -1.022927 -2.155213 0)
			(layer "B.Fab")
			(effects
				(font
					(size 0.7 0.7)
					(thickness 0.15)
				)
				(justify left bottom mirror)
			)
		)
		(property "Datasheet" "https://www.murata.com/products/productdetail?partno=GRM155R61H104KE14%23"
			(at 0 0 0)
			(layer "B.Fab")
			(hide yes)
			(effects
				(font
					(size 1.27 1.27)
					(thickness 0.15)
				)
				(justify mirror)
			)
		)
		(property "Description" "SMD Multilayer Ceramic Capacitor, 0.1 µF, 50 V, 0402 [1005 Metric], ± 10%, X5R, GRM Series"
			(at 0 0 0)
			(layer "B.Fab")
			(hide yes)
			(effects
				(font
					(size 1.27 1.27)
					(thickness 0.15)
				)
				(justify mirror)
			)
		)
		(property "Manufacturer" "Murata"
			(at 0 0 0)
			(unlocked yes)
			(layer "B.Fab")
			(hide yes)
			(effects
				(font
					(size 1 1)
					(thickness 0.15)
				)
				(justify mirror)
			)
		)
		(property "MPN" "GRM155R61H104KE14D"
			(at 0 0 0)
			(unlocked yes)
			(layer "B.Fab")
			(hide yes)
			(effects
				(font
					(size 1 1)
					(thickness 0.15)
				)
				(justify mirror)
			)
		)
		(property "Val" "100n"
			(at 0 0 0)
			(unlocked yes)
			(layer "B.Fab")
			(hide yes)
			(effects
				(font
					(size 1 1)
					(thickness 0.15)
				)
				(justify mirror)
			)
		)
		(property "License" "Apache-2.0"
			(at 0 0 0)
			(unlocked yes)
			(layer "B.Fab")
			(hide yes)
			(effects
				(font
					(size 1 1)
					(thickness 0.15)
				)
				(justify mirror)
			)
		)
		(property "Author" "Antmicro"
			(at 0 0 0)
			(unlocked yes)
			(layer "B.Fab")
			(hide yes)
			(effects
				(font
					(size 1 1)
					(thickness 0.15)
				)
				(justify mirror)
			)
		)
		(property "Voltage" "50V"
			(at 0 0 0)
			(unlocked yes)
			(layer "B.Fab")
			(hide yes)
			(effects
				(font
					(size 1 1)
					(thickness 0.15)
				)
				(justify mirror)
			)
		)
		(property "Dielectric" "X5R"
			(at 0 0 0)
			(unlocked yes)
			(layer "B.Fab")
			(hide yes)
			(effects
				(font
					(size 1 1)
					(thickness 0.15)
				)
				(justify mirror)
			)
		)
		(sheetname "/Recovery USB/")
		(sheetfile "recovery_usb.kicad_sch")
		(attr smd)
		(fp_poly
			(pts
				(xy -0.925 0.47) (xy 0.925 0.47) (xy 0.925 -0.47) (xy -0.925 -0.47)
			)
			(stroke
				(width 0.05)
				(type default)
			)
			(fill no)
			(layer "B.CrtYd")
		)
		(fp_line
			(start 0.504 0.25)
			(end 0.504 -0.248)
			(stroke
				(width 0.15)
				(type solid)
			)
			(layer "B.Fab")
		)
		(fp_line
			(start 0.504 -0.248)
			(end -0.494 -0.248)
			(stroke
				(width 0.15)
				(type solid)
			)
			(layer "B.Fab")
		)
		(fp_line
			(start -0.494 0.25)
			(end 0.504 0.25)
			(stroke
				(width 0.15)
				(type solid)
			)
			(layer "B.Fab")
		)
		(fp_line
			(start -0.494 -0.248)
			(end -0.494 0.25)
			(stroke
				(width 0.15)
				(type solid)
			)
			(layer "B.Fab")
		)
		(fp_text user "${REFERENCE}"
			(at -0.939 -4.599 0)
			(layer "B.Fab")
			(effects
				(font
					(size 0.7 0.7)
					(thickness 0.15)
				)
				(justify left bottom mirror)
			)
		)
		(fp_text user "License: Apache-2.0"
			(at -0.939 -5.799 0)
			(layer "B.Fab")
			(effects
				(font
					(size 0.7 0.7)
					(thickness 0.15)
				)
				(justify left bottom mirror)
			)
		)
		(fp_text user "Author: Antmicro"
			(at -0.939 -3.399 0)
			(layer "B.Fab")
			(effects
				(font
					(size 0.7 0.7)
					(thickness 0.15)
				)
				(justify left bottom mirror)
			)
		)
		(pad "1" smd roundrect
			(at -0.48 0 180)
			(size 0.59 0.64)
			(layers "B.Cu" "B.Mask" "B.Paste")
			(roundrect_rratio 0.25)
			(net 287 "/Recovery USB/USBC2_VBUS")
			(pintype "passive")
		)
		(pad "2" smd roundrect
			(at 0.48 0 180)
			(size 0.59 0.64)
			(layers "B.Cu" "B.Mask" "B.Paste")
			(roundrect_rratio 0.25)
			(net 1 "GND")
			(pintype "passive")
		)
	)
)
